(kicad_pcb
	(version 20221018)
	(generator pcbnew)
	(general
    (thickness 1.7403)
  )
	(paper "A4")
	(title_block
    (title "Data Center RDIMM DDR4 Tester")
    (date "2024-09-30")
    (rev "1.2.4")
		(comment 9 "footprints 403-411 of 690")
	)
	(layers
    (0 "F.Cu" signal)
    (1 "In1.Cu" power)
    (2 "In2.Cu" signal)
    (3 "In3.Cu" power)
    (4 "In4.Cu" power)
    (5 "In5.Cu" signal)
    (6 "In6.Cu" power)
    (7 "In7.Cu" signal)
    (8 "In8.Cu" power)
    (9 "In9.Cu" signal)
    (10 "In10.Cu" power)
    (31 "B.Cu" signal)
    (32 "B.Adhes" user "B.Adhesive")
    (33 "F.Adhes" user "F.Adhesive")
    (34 "B.Paste" user)
    (35 "F.Paste" user)
    (36 "B.SilkS" user "B.Silkscreen")
    (37 "F.SilkS" user "F.Silkscreen")
    (38 "B.Mask" user)
    (39 "F.Mask" user)
    (40 "Dwgs.User" user "User.Drawings")
    (41 "Cmts.User" user "User.Comments")
    (42 "Eco1.User" user "User.Eco1")
    (43 "Eco2.User" user "User.Eco2")
    (44 "Edge.Cuts" user)
    (45 "Margin" user)
    (46 "B.CrtYd" user "B.Courtyard")
    (47 "F.CrtYd" user "F.Courtyard")
    (48 "B.Fab" user)
    (49 "F.Fab" user)
  )
	(footprint "data-center-rdimm-ddr4-tester-footprints:C_0402_1005Metric" (layer "B.Cu")
    (at 160.686328 93.020008 -90)
    (descr "Capacitor SMD 0402")
    (tags "capacitor SMD 0402")
    (property "Author" "Antmicro")
    (property "Dielectric" "X7R")
    (property "License" "Apache-2.0")
    (property "MPN" "GRM155R71H103KA88D")
    (property "Manufacturer" "Murata")
    (property "Sheetfile" "ethernet.kicad_sch")
    (property "Sheetname" "Ethernet")
    (property "Val" "10n")
    (property "Voltage" "50V")
    (property "ki_description" " ")
    (attr smd)
    (fp_text reference "C141" (at -1.449008 -6.503672 90) (layer "B.SilkS")
        (effects (font (size 0.7 0.7) (thickness 0.15)) (justify left bottom mirror))
    )
    (fp_text value "C_10n_0402" (at 0 -1.4 90) (layer "B.Fab") hide
        (effects (font (size 0.7 0.7) (thickness 0.15)) (justify left bottom mirror))
    )
    (fp_text user "${REFERENCE}" (at -0.932 -3.168 90) (layer "B.Fab") hide
        (effects (font (size 0.7 0.7) (thickness 0.15)) (justify left bottom mirror))
    )
    (fp_text user "Author: Antmicro" (at -0.932 -4.17 90) (layer "B.Fab") hide
        (effects (font (size 0.7 0.7) (thickness 0.15)) (justify left bottom mirror))
    )
    (fp_text user "License: Apache-2.0" (at -0.932 -5.17 90) (layer "B.Fab") hide
        (effects (font (size 0.7 0.7) (thickness 0.15)) (justify left bottom mirror))
    )
    (fp_rect (start -0.94 0.47) (end 0.94 -0.47)
      (stroke (width 0.05) (type solid)) (fill none) (layer "B.CrtYd"))
    (fp_rect (start -0.499 0.249) (end 0.499 -0.249)
      (stroke (width 0.15) (type solid)) (fill none) (layer "B.Fab"))
    (pad "1" smd roundrect (at -0.484 0 270) (size 0.59 0.64) (layers "B.Cu" "B.Paste" "B.Mask") (roundrect_rratio 0.25)
      (net 306 "1V2_SYS") (pintype "passive"))
    (pad "2" smd roundrect (at 0.484 0 270) (size 0.59 0.64) (layers "B.Cu" "B.Paste" "B.Mask") (roundrect_rratio 0.25)
      (net 9 "GND") (pintype "passive"))
  )
	(footprint "data-center-rdimm-ddr4-tester-footprints:FB_0603_1608Metric" (layer "B.Cu")
    (at 153.786328 101.274306)
    (property "Author" "Antmicro")
    (property "License" "Apache-2.0")
    (property "MPN" "BLM18PG121SN1D")
    (property "Manufacturer" "Murata")
    (property "Sheetfile" "ethernet.kicad_sch")
    (property "Sheetname" "Ethernet")
    (property "ki_description" "Ferrite Beads WE-TMSB Suppression 240Ohm 200mA ")
    (property "ki_keywords" " Multilayer Suppression Beads ")
    (attr smd)
    (fp_text reference "FB1" (at -1.436328 0.375694 180) (layer "B.SilkS")
        (effects (font (size 0.7 0.7) (thickness 0.15)) (justify left bottom mirror))
    )
    (fp_text value "FB_120Z_2A_0603" (at 0 -1.7 180) (layer "B.Fab") hide
        (effects (font (size 0.7 0.7) (thickness 0.15)) (justify left bottom mirror))
    )
    (fp_text user "License: Apache-2.0" (at -1.653 -5.9 180) (layer "B.Fab") hide
        (effects (font (size 0.7 0.7) (thickness 0.15)) (justify left bottom mirror))
    )
    (fp_text user "Author: Antmicro" (at -1.653 -3.162 180) (layer "B.Fab") hide
        (effects (font (size 0.7 0.7) (thickness 0.15)) (justify left bottom mirror))
    )
    (fp_text user "${REFERENCE}" (at -1.653 -4.6 180) (layer "B.Fab") hide
        (effects (font (size 0.7 0.7) (thickness 0.15)) (justify left bottom mirror))
    )
    (fp_line (start -0.196 -0.406) (end 0.193 -0.406)
      (stroke (width 0.15) (type solid)) (layer "B.SilkS"))
    (fp_line (start -0.196 0.408) (end 0.193 0.408)
      (stroke (width 0.15) (type solid)) (layer "B.SilkS"))
    (fp_rect (start -1.3 0.6) (end 1.3 -0.6)
      (stroke (width 0.05) (type solid)) (fill none) (layer "B.CrtYd"))
    (fp_line (start -0.803 -0.406) (end -0.803 0.408)
      (stroke (width 0.15) (type solid)) (layer "B.Fab"))
    (fp_line (start 0.8 -0.406) (end -0.803 -0.406)
      (stroke (width 0.15) (type solid)) (layer "B.Fab"))
    (fp_line (start 0.8 0.408) (end -0.803 0.408)
      (stroke (width 0.15) (type solid)) (layer "B.Fab"))
    (fp_line (start 0.8 0.408) (end 0.8 -0.406)
      (stroke (width 0.15) (type solid)) (layer "B.Fab"))
    (pad "1" smd roundrect (at -0.891 0) (size 0.762 1.09) (layers "B.Cu" "B.Paste" "B.Mask") (roundrect_rratio 0.15)
      (net 143 "3V3_SYS") (pintype "passive"))
    (pad "2" smd roundrect (at 0.888 0) (size 0.762 1.09) (layers "B.Cu" "B.Paste" "B.Mask") (roundrect_rratio 0.15)
      (net 179 "/Ethernet/AVDDH") (pintype "passive"))
  )
	(footprint "data-center-rdimm-ddr4-tester-footprints:FB_0603_1608Metric" (layer "B.Cu")
    (at 158.9 98.275)
    (property "Author" "Antmicro")
    (property "License" "Apache-2.0")
    (property "MPN" "BLM18PG121SN1D")
    (property "Manufacturer" "Murata")
    (property "Sheetfile" "ethernet.kicad_sch")
    (property "Sheetname" "Ethernet")
    (property "ki_description" "Ferrite Beads WE-TMSB Suppression 240Ohm 200mA ")
    (property "ki_keywords" " Multilayer Suppression Beads ")
    (attr smd)
    (fp_text reference "FB3" (at 0.99 -0.795 180) (layer "B.SilkS")
        (effects (font (size 0.7 0.7) (thickness 0.15)) (justify left bottom mirror))
    )
    (fp_text value "FB_120Z_2A_0603" (at 0 -1.7 180) (layer "B.Fab") hide
        (effects (font (size 0.7 0.7) (thickness 0.15)) (justify left bottom mirror))
    )
    (fp_text user "License: Apache-2.0" (at -1.653 -5.9 180) (layer "B.Fab") hide
        (effects (font (size 0.7 0.7) (thickness 0.15)) (justify left bottom mirror))
    )
    (fp_text user "${REFERENCE}" (at -1.653 -4.6 180) (layer "B.Fab") hide
        (effects (font (size 0.7 0.7) (thickness 0.15)) (justify left bottom mirror))
    )
    (fp_text user "Author: Antmicro" (at -1.653 -3.162 180) (layer "B.Fab") hide
        (effects (font (size 0.7 0.7) (thickness 0.15)) (justify left bottom mirror))
    )
    (fp_line (start -0.196 -0.406) (end 0.193 -0.406)
      (stroke (width 0.15) (type solid)) (layer "B.SilkS"))
    (fp_line (start -0.196 0.408) (end 0.193 0.408)
      (stroke (width 0.15) (type solid)) (layer "B.SilkS"))
    (fp_rect (start -1.3 0.6) (end 1.3 -0.6)
      (stroke (width 0.05) (type solid)) (fill none) (layer "B.CrtYd"))
    (fp_line (start -0.803 -0.406) (end -0.803 0.408)
      (stroke (width 0.15) (type solid)) (layer "B.Fab"))
    (fp_line (start 0.8 -0.406) (end -0.803 -0.406)
      (stroke (width 0.15) (type solid)) (layer "B.Fab"))
    (fp_line (start 0.8 0.408) (end -0.803 0.408)
      (stroke (width 0.15) (type solid)) (layer "B.Fab"))
    (fp_line (start 0.8 0.408) (end 0.8 -0.406)
      (stroke (width 0.15) (type solid)) (layer "B.Fab"))
    (pad "1" smd roundrect (at -0.891 0) (size 0.762 1.09) (layers "B.Cu" "B.Paste" "B.Mask") (roundrect_rratio 0.15)
      (net 177 "/Ethernet/AVDDL") (pintype "passive"))
    (pad "2" smd roundrect (at 0.888 0) (size 0.762 1.09) (layers "B.Cu" "B.Paste" "B.Mask") (roundrect_rratio 0.15)
      (net 306 "1V2_SYS") (pintype "passive"))
  )
	(footprint "data-center-rdimm-ddr4-tester-footprints:R_0402_1005Metric" (layer "B.Cu")
    (at 166.423925 131.05 180)
    (descr "Resistor SMD 0402")
    (tags "resistor SMD 0402")
    (property "Author" "Antmicro")
    (property "License" "Apache-2.0")
    (property "MPN" "CR0402-FX-2200GLF")
    (property "Manufacturer" "Bourns")
    (property "Sheetfile" "ethernet.kicad_sch")
    (property "Sheetname" "Ethernet")
    (property "Tolerance" "1%")
    (property "Val" "220R")
    (property "ki_description" "220R resistor in 0402 package with 1% tolerance")
    (attr smd)
    (fp_text reference "R62" (at -1.096075 0.59) (layer "B.SilkS")
        (effects (font (size 0.7 0.7) (thickness 0.15)) (justify left bottom mirror))
    )
    (fp_text value "R_220R_0402" (at 0 -1.4) (layer "B.Fab") hide
        (effects (font (size 0.7 0.7) (thickness 0.15)) (justify left bottom mirror))
    )
    (fp_text user "${REFERENCE}" (at -0.95 -3.168) (layer "B.Fab") hide
        (effects (font (size 0.7 0.7) (thickness 0.15)) (justify left bottom mirror))
    )
    (fp_text user "License: Apache-2.0" (at -0.95 -5.169) (layer "B.Fab") hide
        (effects (font (size 0.7 0.7) (thickness 0.15)) (justify left bottom mirror))
    )
    (fp_text user "Author: Antmicro" (at -0.95 -4.169) (layer "B.Fab") hide
        (effects (font (size 0.7 0.7) (thickness 0.15)) (justify left bottom mirror))
    )
    (fp_rect (start -0.93 0.47) (end 0.93 -0.47)
      (stroke (width 0.05) (type solid)) (fill none) (layer "B.CrtYd"))
    (fp_rect (start -0.5 0.25) (end 0.5 -0.25)
      (stroke (width 0.15) (type solid)) (fill none) (layer "B.Fab"))
    (pad "1" smd roundrect (at -0.485 0 180) (size 0.59 0.64) (layers "B.Cu" "B.Paste" "B.Mask") (roundrect_rratio 0.25)
      (net 113 "Net-(J2-LED_YEL+)") (pintype "passive"))
    (pad "2" smd roundrect (at 0.485 0 180) (size 0.59 0.64) (layers "B.Cu" "B.Paste" "B.Mask") (roundrect_rratio 0.25)
      (net 143 "3V3_SYS") (pintype "passive"))
  )
	(footprint "data-center-rdimm-ddr4-tester-footprints:R_0402_1005Metric" (layer "B.Cu")
    (at 156.072849 131.076396 180)
    (descr "Resistor SMD 0402")
    (tags "resistor SMD 0402")
    (property "Author" "Antmicro")
    (property "License" "Apache-2.0")
    (property "MPN" "CR0402-FX-2200GLF")
    (property "Manufacturer" "Bourns")
    (property "Sheetfile" "ethernet.kicad_sch")
    (property "Sheetname" "Ethernet")
    (property "Tolerance" "1%")
    (property "Val" "220R")
    (property "ki_description" "220R resistor in 0402 package with 1% tolerance")
    (attr smd)
    (fp_text reference "R67" (at -0.957151 0.596396) (layer "B.SilkS")
        (effects (font (size 0.7 0.7) (thickness 0.15)) (justify left bottom mirror))
    )
    (fp_text value "R_220R_0402" (at 0 -1.4) (layer "B.Fab") hide
        (effects (font (size 0.7 0.7) (thickness 0.15)) (justify left bottom mirror))
    )
    (fp_text user "Author: Antmicro" (at -0.95 -4.169) (layer "B.Fab") hide
        (effects (font (size 0.7 0.7) (thickness 0.15)) (justify left bottom mirror))
    )
    (fp_text user "${REFERENCE}" (at -0.95 -3.168) (layer "B.Fab") hide
        (effects (font (size 0.7 0.7) (thickness 0.15)) (justify left bottom mirror))
    )
    (fp_text user "License: Apache-2.0" (at -0.95 -5.169) (layer "B.Fab") hide
        (effects (font (size 0.7 0.7) (thickness 0.15)) (justify left bottom mirror))
    )
    (fp_rect (start -0.93 0.47) (end 0.93 -0.47)
      (stroke (width 0.05) (type solid)) (fill none) (layer "B.CrtYd"))
    (fp_rect (start -0.5 0.25) (end 0.5 -0.25)
      (stroke (width 0.15) (type solid)) (fill none) (layer "B.Fab"))
    (pad "1" smd roundrect (at -0.485 0 180) (size 0.59 0.64) (layers "B.Cu" "B.Paste" "B.Mask") (roundrect_rratio 0.25)
      (net 112 "Net-(J2-LED_GRN+)") (pintype "passive"))
    (pad "2" smd roundrect (at 0.485 0 180) (size 0.59 0.64) (layers "B.Cu" "B.Paste" "B.Mask") (roundrect_rratio 0.25)
      (net 143 "3V3_SYS") (pintype "passive"))
  )
	(footprint "data-center-rdimm-ddr4-tester-footprints:R_0402_1005Metric" (layer "B.Cu")
    (at 157.671328 88.645008 -90)
    (descr "Resistor SMD 0402")
    (tags "resistor SMD 0402")
    (property "Author" "Antmicro")
    (property "License" "Apache-2.0")
    (property "MPN" "CR0402-FX-2201GLF")
    (property "Manufacturer" "Bourns")
    (property "Sheetfile" "ethernet.kicad_sch")
    (property "Sheetname" "Ethernet")
    (property "Tolerance" "1%")
    (property "Val" "2k2")
    (property "ki_description" "2k2 resistor in 0402 package with 1% tolerance")
    (attr smd)
    (fp_text reference "R77" (at -1.165008 -7.958672 90) (layer "B.SilkS")
        (effects (font (size 0.7 0.7) (thickness 0.15)) (justify left bottom mirror))
    )
    (fp_text value "R_2k2_0402" (at 0 -1.4 90) (layer "B.Fab") hide
        (effects (font (size 0.7 0.7) (thickness 0.15)) (justify left bottom mirror))
    )
    (fp_text user "License: Apache-2.0" (at -0.95 -5.169 90) (layer "B.Fab") hide
        (effects (font (size 0.7 0.7) (thickness 0.15)) (justify left bottom mirror))
    )
    (fp_text user "${REFERENCE}" (at -0.95 -3.168 90) (layer "B.Fab") hide
        (effects (font (size 0.7 0.7) (thickness 0.15)) (justify left bottom mirror))
    )
    (fp_text user "Author: Antmicro" (at -0.95 -4.169 90) (layer "B.Fab") hide
        (effects (font (size 0.7 0.7) (thickness 0.15)) (justify left bottom mirror))
    )
    (fp_rect (start -0.93 0.47) (end 0.93 -0.47)
      (stroke (width 0.05) (type solid)) (fill none) (layer "B.CrtYd"))
    (fp_rect (start -0.5 0.25) (end 0.5 -0.25)
      (stroke (width 0.15) (type solid)) (fill none) (layer "B.Fab"))
    (pad "1" smd roundrect (at -0.485 0 270) (size 0.59 0.64) (layers "B.Cu" "B.Paste" "B.Mask") (roundrect_rratio 0.25)
      (net 26 "ETH_RXD0") (pintype "passive"))
    (pad "2" smd roundrect (at 0.485 0 270) (size 0.59 0.64) (layers "B.Cu" "B.Paste" "B.Mask") (roundrect_rratio 0.25)
      (net 9 "GND") (pintype "passive"))
  )
	(footprint "data-center-rdimm-ddr4-tester-footprints:R_0402_1005Metric" (layer "B.Cu")
    (at 153.886328 92.520008)
    (descr "Resistor SMD 0402")
    (tags "resistor SMD 0402")
    (property "Author" "Antmicro")
    (property "License" "Apache-2.0")
    (property "MPN" "CR0402-FX-1001GLF")
    (property "Manufacturer" "Bourns")
    (property "Sheetfile" "ethernet.kicad_sch")
    (property "Sheetname" "Ethernet")
    (property "Tolerance" "1%")
    (property "Val" "1k")
    (property "ki_description" "1k resistor in 0402 package with 1% tolerance")
    (attr smd)
    (fp_text reference "R78" (at -0.946328 0.399992 180) (layer "B.SilkS")
        (effects (font (size 0.7 0.7) (thickness 0.15)) (justify left bottom mirror))
    )
    (fp_text value "R_1k_0402" (at 0 -1.4 180) (layer "B.Fab") hide
        (effects (font (size 0.7 0.7) (thickness 0.15)) (justify left bottom mirror))
    )
    (fp_text user "License: Apache-2.0" (at -0.95 -5.169 180) (layer "B.Fab") hide
        (effects (font (size 0.7 0.7) (thickness 0.15)) (justify left bottom mirror))
    )
    (fp_text user "Author: Antmicro" (at -0.95 -4.169 180) (layer "B.Fab") hide
        (effects (font (size 0.7 0.7) (thickness 0.15)) (justify left bottom mirror))
    )
    (fp_text user "${REFERENCE}" (at -0.95 -3.168 180) (layer "B.Fab") hide
        (effects (font (size 0.7 0.7) (thickness 0.15)) (justify left bottom mirror))
    )
    (fp_rect (start -0.93 0.47) (end 0.93 -0.47)
      (stroke (width 0.05) (type solid)) (fill none) (layer "B.CrtYd"))
    (fp_rect (start -0.5 0.25) (end 0.5 -0.25)
      (stroke (width 0.15) (type solid)) (fill none) (layer "B.Fab"))
    (pad "1" smd roundrect (at -0.485 0) (size 0.59 0.64) (layers "B.Cu" "B.Paste" "B.Mask") (roundrect_rratio 0.25)
      (net 29 "ETH_MDIO") (pintype "passive"))
    (pad "2" smd roundrect (at 0.485 0) (size 0.59 0.64) (layers "B.Cu" "B.Paste" "B.Mask") (roundrect_rratio 0.25)
      (net 143 "3V3_SYS") (pintype "passive"))
  )
	(footprint "data-center-rdimm-ddr4-tester-footprints:R_0402_1005Metric" (layer "B.Cu")
    (at 159.636328 89.580008 -90)
    (descr "Resistor SMD 0402")
    (tags "resistor SMD 0402")
    (property "Author" "Antmicro")
    (property "DNP" "DNP")
    (property "License" "Apache-2.0")
    (property "MPN" "CR0402-FX-2201GLF")
    (property "Manufacturer" "Bourns")
    (property "Sheetfile" "ethernet.kicad_sch")
    (property "Sheetname" "Ethernet")
    (property "Tolerance" "1%")
    (property "Val" "2k2")
    (property "dnp" "")
    (property "exclude_from_bom" "")
    (property "ki_description" "2k2 resistor in 0402 package with 1% tolerance")
    (attr exclude_from_pos_files exclude_from_bom)
    (fp_text reference "R90" (at -1.165008 -7.958672 90) (layer "B.SilkS")
        (effects (font (size 0.7 0.7) (thickness 0.15)) (justify left bottom mirror))
    )
    (fp_text value "R_2k2_0402" (at 0 -1.4 90) (layer "B.Fab") hide
        (effects (font (size 0.7 0.7) (thickness 0.15)) (justify left bottom mirror))
    )
    (fp_text user "Author: Antmicro" (at -0.95 -4.169 90) (layer "B.Fab") hide
        (effects (font (size 0.7 0.7) (thickness 0.15)) (justify left bottom mirror))
    )
    (fp_text user "License: Apache-2.0" (at -0.95 -5.169 90) (layer "B.Fab") hide
        (effects (font (size 0.7 0.7) (thickness 0.15)) (justify left bottom mirror))
    )
    (fp_text user "${REFERENCE}" (at -0.95 -3.168 90) (layer "B.Fab") hide
        (effects (font (size 0.7 0.7) (thickness 0.15)) (justify left bottom mirror))
    )
    (fp_rect (start -0.93 0.47) (end 0.93 -0.47)
      (stroke (width 0.05) (type solid)) (fill none) (layer "B.CrtYd"))
    (fp_rect (start -0.5 0.25) (end 0.5 -0.25)
      (stroke (width 0.15) (type solid)) (fill none) (layer "B.Fab"))
    (pad "1" smd roundrect (at -0.485 0 270) (size 0.59 0.64) (layers "B.Cu" "B.Paste" "B.Mask") (roundrect_rratio 0.25)
      (net 41 "ETH_RXD2") (pintype "passive"))
    (pad "2" smd roundrect (at 0.485 0 270) (size 0.59 0.64) (layers "B.Cu" "B.Paste" "B.Mask") (roundrect_rratio 0.25)
      (net 9 "GND") (pintype "passive"))
  )
	(footprint "data-center-rdimm-ddr4-tester-footprints:R_0402_1005Metric" (layer "B.Cu")
    (at 158.186328 90.460008)
    (descr "Resistor SMD 0402")
    (tags "resistor SMD 0402")
    (property "Author" "Antmicro")
    (property "License" "Apache-2.0")
    (property "MPN" "CR0402-FX-2201GLF")
    (property "Manufacturer" "Bourns")
    (property "Sheetfile" "ethernet.kicad_sch")
    (property "Sheetname" "Ethernet")
    (property "Tolerance" "1%")
    (property "Val" "2k2")
    (property "ki_description" "2k2 resistor in 0402 package with 1% tolerance")
    (attr smd)
    (fp_text reference "R92" (at 8.413672 0.379992 180) (layer "B.SilkS")
        (effects (font (size 0.7 0.7) (thickness 0.15)) (justify left bottom mirror))
    )
    (fp_text value "R_2k2_0402" (at 0 -1.4 180) (layer "B.Fab") hide
        (effects (font (size 0.7 0.7) (thickness 0.15)) (justify left bottom mirror))
    )
    (fp_text user "${REFERENCE}" (at -0.95 -3.168 180) (layer "B.Fab") hide
        (effects (font (size 0.7 0.7) (thickness 0.15)) (justify left bottom mirror))
    )
    (fp_text user "Author: Antmicro" (at -0.95 -4.169 180) (layer "B.Fab") hide
        (effects (font (size 0.7 0.7) (thickness 0.15)) (justify left bottom mirror))
    )
    (fp_text user "License: Apache-2.0" (at -0.95 -5.169 180) (layer "B.Fab") hide
        (effects (font (size 0.7 0.7) (thickness 0.15)) (justify left bottom mirror))
    )
    (fp_rect (start -0.93 0.47) (end 0.93 -0.47)
      (stroke (width 0.05) (type solid)) (fill none) (layer "B.CrtYd"))
    (fp_rect (start -0.5 0.25) (end 0.5 -0.25)
      (stroke (width 0.15) (type solid)) (fill none) (layer "B.Fab"))
    (pad "1" smd roundrect (at -0.485 0) (size 0.59 0.64) (layers "B.Cu" "B.Paste" "B.Mask") (roundrect_rratio 0.25)
      (net 38 "ETH_RX_DV") (pintype "passive"))
    (pad "2" smd roundrect (at 0.485 0) (size 0.59 0.64) (layers "B.Cu" "B.Paste" "B.Mask") (roundrect_rratio 0.25)
      (net 9 "GND") (pintype "passive"))
  )
)
